FILE_TYPE = CONNECTIVITY;
{Allegro Design Entry HDL 16.6-p007 (v16-6-112F) 10/10/2012}
"PAGE_NUMBER" = 178;
0"NC";
1"P3V3_STBY\g";
2"P3V3_STBY\g";
3"SGPIO_PCH_SATA_DOUT0_R";
4"SGPIO_PCH_SSATA_CLOCK_R";
5"SGPIO_PCH_SSATA_DOUT0_R";
6"SGPIO_PCH_SSATA_LOAD_R";
7"SGPIO_PCH_SATA_CLOCK_R";
8"SGPIO_PCH_SATA_LOAD_R";
9"SGPIO_PCH_SSATA_DOUT0";
10"SGPIO_PCH_SSATA_LOAD";
11"SGPIO_PCH_SSATA_CLOCK";
12"SGPIO_PCH_SATA_LOAD";
13"SGPIO_PCH_SATA_DOUT0";
14"SGPIO_PCH_SATA_CLOCK";
%"RES"
"1","(-800,3725)","0","mstr_discrete","I1";
;
CDS_SEC"1"
LOCATION"R8D20"
PART_NUMBER"G21796-047"
VALUE"49.9"
TOLERANCE"1%"
PACK_TYPE"0402"
MATERIAL"CHIP"
WATTAGE"1/16W"
CDS_LIB"mstr_discrete"
SEC_TYPE"0402"
BOM_COST"ST_SATA"
SEC"1"
CDS_LOCATION"R8D20"
ROOM"ST_SATA";
"B"
$PN"2"8;
"A"
$PN"1"12;
%"RES"
"1","(-800,3425)","0","mstr_discrete","I11";
;
CDS_SEC"1"
CDS_LOCATION"R2N31"
LOCATION"R2N31"
PART_NUMBER"G21796-047"
VALUE"49.9"
TOLERANCE"1%"
PACK_TYPE"0402"
MATERIAL"CHIP"
WATTAGE"1/16W"
CDS_LIB"mstr_discrete"
SEC_TYPE"0402"
BOM_COST"ST_SATA"
SEC"1"
ROOM"ST_SATA";
"B"
$PN"2"7;
"A"
$PN"1"14;
%"RES"
"2","(225,4125)","2","mstr_discrete","I12";
;
CDS_SEC"1"
LOCATION"R2L15"
PART_NUMBER"G21796-001"
VALUE"2.0K"
TOLERANCE"1%"
PACK_TYPE"0402"
MATERIAL"CHIP"
WATTAGE"1/16W"
CDS_LIB"mstr_discrete"
SEC_TYPE"0402"
BOM_COST"ST_SATA"
SEC"1"
CDS_LOCATION"R2L15"
ROOM"ST_SATA";
"A"
$PN"1"2;
"B"
$PN"2"3;
%"RES"
"2","(575,4125)","2","mstr_discrete","I13";
;
CDS_SEC"1"
LOCATION"R2L11"
VALUE"2.0K"
TOLERANCE"1%"
MATERIAL"CHIP"
WATTAGE"1/16W"
PART_NUMBER"G21796-001"
PACK_TYPE"0402"
CDS_LIB"mstr_discrete"
SEC_TYPE"0402"
BOM_COST"ST_SATA"
SEC"1"
CDS_LOCATION"R2L11"
ROOM"ST_SATA";
"A"
$PN"1"2;
"B"
$PN"2"7;
%"RES"
"2","(475,2225)","2","mstr_discrete","I17";
;
CDS_SEC"1"
LOCATION"R2L6"
PART_NUMBER"G21796-001"
VALUE"2.0K"
TOLERANCE"1%"
PACK_TYPE"0402"
MATERIAL"CHIP"
WATTAGE"1/16W"
BOM_COST"ST_SATA"
SEC_TYPE"0402"
CDS_LIB"mstr_discrete"
SEC"1"
CDS_LOCATION"R2L6"
ROOM"ST_SATA";
"A"
$PN"1"1;
"B"
$PN"2"4;
%"RES"
"2","(125,2225)","2","mstr_discrete","I18";
;
CDS_SEC"1"
LOCATION"R2L4"
PART_NUMBER"G21796-001"
VALUE"2.0K"
TOLERANCE"1%"
PACK_TYPE"0402"
MATERIAL"CHIP"
WATTAGE"1/16W"
BOM_COST"ST_SATA"
SEC_TYPE"0402"
CDS_LIB"mstr_discrete"
SEC"1"
CDS_LOCATION"R2L4"
ROOM"ST_SATA";
"A"
$PN"1"1;
"B"
$PN"2"5;
%"P3V3_STBY"
"1","(-200,2625)","0","mstr_symbols","I19";
;
VOLTAGE"3.3V"
CDS_LIB"mstr_symbols"
SIZE"1B"
BODY_TYPE"PLUMBING"
HDL_POWER"P3V3_STBY";
"G\NAC"1;
%"RES"
"2","(-200,4125)","2","mstr_discrete","I2";
;
CDS_SEC"1"
LOCATION"R2L12"
PART_NUMBER"G21796-001"
VALUE"2.0K"
TOLERANCE"1%"
PACK_TYPE"0402"
MATERIAL"CHIP"
WATTAGE"1/16W"
BOM_COST"ST_SATA"
SEC_TYPE"0402"
CDS_LIB"mstr_discrete"
SEC"1"
CDS_LOCATION"R2L12"
ROOM"ST_SATA";
"A"
$PN"1"2;
"B"
$PN"2"8;
%"RES"
"2","(-200,2225)","2","mstr_discrete","I20";
;
CDS_SEC"1"
TOLERANCE"1%"
PACK_TYPE"0402"
MATERIAL"CHIP"
WATTAGE"1/16W"
PART_NUMBER"G21796-001"
VALUE"2.0K"
LOCATION"R2L5"
CDS_LIB"mstr_discrete"
SEC_TYPE"0402"
BOM_COST"ST_SATA"
SEC"1"
CDS_LOCATION"R2L5"
ROOM"ST_SATA";
"A"
$PN"1"1;
"B"
$PN"2"6;
%"RES"
"1","(-800,1675)","0","mstr_discrete","I21";
;
CDS_SEC"1"
LOCATION"R8B29"
VALUE"49.9"
TOLERANCE"1%"
MATERIAL"CHIP"
WATTAGE"1/16W"
PART_NUMBER"G21796-047"
PACK_TYPE"0402"
BOM_COST"ST_SATA"
SEC_TYPE"0402"
CDS_LIB"mstr_discrete"
SEC"1"
CDS_LOCATION"R8B29"
ROOM"ST_SATA";
"B"
$PN"2"5;
"A"
$PN"1"9;
%"RES"
"1","(-800,1825)","0","mstr_discrete","I22";
;
CDS_SEC"1"
LOCATION"R2N19"
VALUE"49.9"
TOLERANCE"1%"
MATERIAL"CHIP"
WATTAGE"1/16W"
PART_NUMBER"G21796-047"
PACK_TYPE"0402"
BOM_COST"ST_SATA"
SEC_TYPE"0402"
CDS_LIB"mstr_discrete"
SEC"1"
CDS_LOCATION"R2N19"
ROOM"ST_SATA";
"B"
$PN"2"6;
"A"
$PN"1"10;
%"RES"
"1","(-800,1525)","0","mstr_discrete","I23";
;
CDS_SEC"1"
LOCATION"R2N22"
PART_NUMBER"G21796-047"
VALUE"49.9"
TOLERANCE"1%"
PACK_TYPE"0402"
MATERIAL"CHIP"
WATTAGE"1/16W"
BOM_COST"ST_SATA"
SEC_TYPE"0402"
CDS_LIB"mstr_discrete"
SEC"1"
CDS_LOCATION"R2N22"
ROOM"ST_SATA";
"B"
$PN"2"4;
"A"
$PN"1"11;
%"P3V3_STBY"
"1","(-200,4525)","0","mstr_symbols","I5";
;
VOLTAGE"3.3V"
SIZE"1B"
CDS_LIB"mstr_symbols"
BODY_TYPE"PLUMBING"
HDL_POWER"P3V3_STBY";
"G\NAC"2;
%"RES"
"1","(-800,3575)","0","mstr_discrete","I8";
;
CDS_SEC"1"
LOCATION"R8D19"
PART_NUMBER"G21796-047"
VALUE"49.9"
TOLERANCE"1%"
PACK_TYPE"0402"
MATERIAL"CHIP"
WATTAGE"1/16W"
CDS_LIB"mstr_discrete"
SEC_TYPE"0402"
BOM_COST"ST_SATA"
SEC"1"
CDS_LOCATION"R8D19"
ROOM"ST_SATA";
"B"
$PN"2"3;
"A"
$PN"1"13;
END.
